# S9S_MB_2U (Grand Teton) — schematic netlist excerpt (pin names and nets, part order shuffled) for the footprints in the layout excerpt that follows; sources: Cadence DE-HDL packaged netlist, KiCad conversion of 03242023_DA0F0TMBIJ0_F0T_Motherboard_J_brd_V01_OCP.brd

R1816  Q_RES  0 5% CHIP  pkg 0402LF  page 240 : A = PWRGD_PS_PWROK ; B = PWRGD_PS_PWROK_R
C1364  Q_CAP  22UF 4V 20% X6S  pkg C0402  page 80 : A = PVNN_MAIN_CPU0 ; B = GND

(kicad_pcb
	(version 20260206)
	(generator "pcbnew")
	(generator_version "10.0")
	(general
		(thickness 1.6)
		(legacy_teardrops no)
	)
	(paper "A4")
	(title_block
		(title "03242023_DA0F0TMBIJ0_F0T_Motherboard_J_brd_V01_OCP.brd")
		(comment 1 "Grand Teton / footprints 5779-5780 of 6105")
	)
	(layers
		(0 "F.Cu" signal "TOP")
		(4 "In1.Cu" signal "GND")
		(6 "In2.Cu" signal "IN1")
		(8 "In3.Cu" signal "GND1")
		(10 "In4.Cu" signal "IN2")
		(12 "In5.Cu" signal "GND2")
		(14 "In6.Cu" signal "IN3")
		(16 "In7.Cu" signal "GND3")
		(18 "In8.Cu" signal "VCC")
		(20 "In9.Cu" signal "VCC1")
		(22 "In10.Cu" signal "GND4")
		(24 "In11.Cu" signal "IN4")
		(26 "In12.Cu" signal "GND5")
		(28 "In13.Cu" signal "IN5")
		(30 "In14.Cu" signal "GND6")
		(32 "In15.Cu" signal "IN6")
		(34 "In16.Cu" signal "GND7")
		(2 "B.Cu" signal "BOTTOM")
		(9 "F.Adhes" user "F.Adhesive")
		(11 "B.Adhes" user "B.Adhesive")
		(13 "F.Paste" user "Package Geometry/Pastemask Top")
		(15 "B.Paste" user "Package Geometry/Pastemask Bottom")
		(5 "F.SilkS" user "Ref Des/Silkscreen Top")
		(7 "B.SilkS" user "Ref Des/Silkscreen Bottom")
		(1 "F.Mask" user "Board Geometry/Soldermask Top")
		(3 "B.Mask" user "Board Geometry/Soldermask Bottom")
		(17 "Dwgs.User" user "User.Drawings")
		(19 "Cmts.User" user "User.Comments")
		(21 "Eco1.User" user "User.Eco1")
		(23 "Eco2.User" user "User.Eco2")
		(25 "Edge.Cuts" user "Board Geometry/Outline")
		(27 "Margin" user)
		(31 "F.CrtYd" user "Package Geometry/Place Bound Top")
		(29 "B.CrtYd" user "Package Geometry/Place Bound Bottom")
		(35 "F.Fab" user "Ref Des/Assembly Top")
		(33 "B.Fab" user "Ref Des/Assembly Bottom")
	)
	(footprint ""
		(layer "B.Cu")
		(at 145.18132 -13.762228 90)
		(property "Reference" "R1816"
			(at 0 0 90)
			(layer "B.SilkS")
			(hide yes)
			(effects
				(font
					(size 1.27 1.27)
				)
				(justify mirror)
			)
		)
		(property "Value" ""
			(at 0 0 90)
			(layer "B.Fab")
			(effects
				(font
					(size 1.27 1.27)
				)
				(justify mirror)
			)
		)
		(duplicate_pad_numbers_are_jumpers no)
		(fp_line
			(start 0.7874 -0.4064)
			(end -0.7874 -0.4064)
			(stroke
				(width 0.1524)
				(type default)
			)
			(layer "B.SilkS")
		)
		(fp_line
			(start -0.7874 -0.4064)
			(end -0.7874 0.4064)
			(stroke
				(width 0.1524)
				(type default)
			)
			(layer "B.SilkS")
		)
		(fp_line
			(start 0.7874 0.4064)
			(end 0.7874 -0.4064)
			(stroke
				(width 0.1524)
				(type default)
			)
			(layer "B.SilkS")
		)
		(fp_line
			(start -0.7874 0.4064)
			(end 0.7874 0.4064)
			(stroke
				(width 0.1524)
				(type default)
			)
			(layer "B.SilkS")
		)
		(fp_line
			(start 0.67945 -0.305054)
			(end 0.12065 -0.305054)
			(stroke
				(width 0.1)
				(type default)
			)
			(layer "B.Fab")
		)
		(fp_line
			(start 0.12065 -0.305054)
			(end 0.12065 -0.2794)
			(stroke
				(width 0.1)
				(type default)
			)
			(layer "B.Fab")
		)
		(fp_line
			(start -0.12065 -0.3048)
			(end -0.67945 -0.3048)
			(stroke
				(width 0.1)
				(type default)
			)
			(layer "B.Fab")
		)
		(fp_line
			(start -0.67945 -0.3048)
			(end -0.67945 0.3048)
			(stroke
				(width 0.1)
				(type default)
			)
			(layer "B.Fab")
		)
		(fp_line
			(start 0.12065 -0.2794)
			(end -0.12065 -0.2794)
			(stroke
				(width 0.1)
				(type default)
			)
			(layer "B.Fab")
		)
		(fp_line
			(start -0.12065 -0.2794)
			(end -0.12065 -0.3048)
			(stroke
				(width 0.1)
				(type default)
			)
			(layer "B.Fab")
		)
		(fp_line
			(start 0.12065 0.2794)
			(end 0.12065 0.3048)
			(stroke
				(width 0.1)
				(type default)
			)
			(layer "B.Fab")
		)
		(fp_line
			(start -0.120396 0.2794)
			(end 0.12065 0.2794)
			(stroke
				(width 0.1)
				(type default)
			)
			(layer "B.Fab")
		)
		(fp_line
			(start 0.67945 0.3048)
			(end 0.67945 -0.305054)
			(stroke
				(width 0.1)
				(type default)
			)
			(layer "B.Fab")
		)
		(fp_line
			(start 0.12065 0.3048)
			(end 0.67945 0.3048)
			(stroke
				(width 0.1)
				(type default)
			)
			(layer "B.Fab")
		)
		(fp_line
			(start -0.120396 0.3048)
			(end -0.120396 0.2794)
			(stroke
				(width 0.1)
				(type default)
			)
			(layer "B.Fab")
		)
		(fp_line
			(start -0.67945 0.3048)
			(end -0.120396 0.3048)
			(stroke
				(width 0.1)
				(type default)
			)
			(layer "B.Fab")
		)
		(pad "1" smd circle
			(at 0.40005 0 270)
			(size 0 0)
			(layers "B.Cu" "B.Mask" "B.Paste")
			(net "PWRGD_PS_PWROK")
		)
		(pad "2" smd circle
			(at -0.40005 0 270)
			(size 0 0)
			(layers "B.Cu" "B.Mask" "B.Paste")
			(net "PWRGD_PS_PWROK_R")
		)
	)
	(footprint ""
		(layer "B.Cu")
		(at 446.941448 -181.977792 180)
		(property "Reference" "C1364"
			(at 0 0 0)
			(layer "B.SilkS")
			(hide yes)
			(effects
				(font
					(size 1.27 1.27)
				)
				(justify mirror)
			)
		)
		(property "Value" ""
			(at 0 0 0)
			(layer "B.Fab")
			(effects
				(font
					(size 1.27 1.27)
				)
				(justify mirror)
			)
		)
		(duplicate_pad_numbers_are_jumpers no)
		(fp_line
			(start 0.7874 0.4064)
			(end 0.7874 -0.4064)
			(stroke
				(width 0.1524)
				(type default)
			)
			(layer "B.SilkS")
		)
		(fp_line
			(start 0.7874 -0.4064)
			(end -0.7874 -0.4064)
			(stroke
				(width 0.1524)
				(type default)
			)
			(layer "B.SilkS")
		)
		(fp_line
			(start -0.7874 0.4064)
			(end 0.7874 0.4064)
			(stroke
				(width 0.1524)
				(type default)
			)
			(layer "B.SilkS")
		)
		(fp_line
			(start -0.7874 -0.4064)
			(end -0.7874 0.4064)
			(stroke
				(width 0.1524)
				(type default)
			)
			(layer "B.SilkS")
		)
		(fp_line
			(start 0.67945 0.3048)
			(end 0.67945 -0.305054)
			(stroke
				(width 0.1)
				(type default)
			)
			(layer "B.Fab")
		)
		(fp_line
			(start 0.67945 -0.305054)
			(end 0.12065 -0.305054)
			(stroke
				(width 0.1)
				(type default)
			)
			(layer "B.Fab")
		)
		(fp_line
			(start 0.12065 0.3048)
			(end 0.67945 0.3048)
			(stroke
				(width 0.1)
				(type default)
			)
			(layer "B.Fab")
		)
		(fp_line
			(start 0.12065 0.2794)
			(end 0.12065 0.3048)
			(stroke
				(width 0.1)
				(type default)
			)
			(layer "B.Fab")
		)
		(fp_line
			(start 0.12065 -0.2794)
			(end -0.12065 -0.2794)
			(stroke
				(width 0.1)
				(type default)
			)
			(layer "B.Fab")
		)
		(fp_line
			(start 0.12065 -0.305054)
			(end 0.12065 -0.2794)
			(stroke
				(width 0.1)
				(type default)
			)
			(layer "B.Fab")
		)
		(fp_line
			(start -0.120396 0.3048)
			(end -0.120396 0.2794)
			(stroke
				(width 0.1)
				(type default)
			)
			(layer "B.Fab")
		)
		(fp_line
			(start -0.120396 0.2794)
			(end 0.12065 0.2794)
			(stroke
				(width 0.1)
				(type default)
			)
			(layer "B.Fab")
		)
		(fp_line
			(start -0.12065 -0.2794)
			(end -0.12065 -0.3048)
			(stroke
				(width 0.1)
				(type default)
			)
			(layer "B.Fab")
		)
		(fp_line
			(start -0.12065 -0.3048)
			(end -0.67945 -0.3048)
			(stroke
				(width 0.1)
				(type default)
			)
			(layer "B.Fab")
		)
		(fp_line
			(start -0.67945 0.3048)
			(end -0.120396 0.3048)
			(stroke
				(width 0.1)
				(type default)
			)
			(layer "B.Fab")
		)
		(fp_line
			(start -0.67945 -0.3048)
			(end -0.67945 0.3048)
			(stroke
				(width 0.1)
				(type default)
			)
			(layer "B.Fab")
		)
		(pad "1" smd circle
			(at 0.40005 0)
			(size 0 0)
			(layers "B.Cu" "B.Mask" "B.Paste")
			(net "PVNN_MAIN_CPU0")
		)
		(pad "2" smd circle
			(at -0.40005 0)
			(size 0 0)
			(layers "B.Cu" "B.Mask" "B.Paste")
			(net "GND")
		)
	)
)
